(kicad_pcb
	(version 20260206)
	(generator "pcbnew")
	(generator_version "10.0")
	(general
		(thickness 1.6)
		(legacy_teardrops no)
	)
	(paper "A4")
	(title_block
		(title "04192023_DAF0TMB3IC0_F0TG_MB_C_brd_V02_OCP.brd")
		(comment 1 "Grand Teton / footprint 4346 of 8354 (U6010), pads 337-354 of 354")
	)
	(layers
		(0 "F.Cu" signal "TOP")
		(4 "In1.Cu" signal "GND")
		(6 "In2.Cu" signal "IN1")
		(8 "In3.Cu" signal "GND1")
		(10 "In4.Cu" signal "IN2")
		(12 "In5.Cu" signal "GND2")
		(14 "In6.Cu" signal "IN3")
		(16 "In7.Cu" signal "GND3")
		(18 "In8.Cu" signal "VCC")
		(20 "In9.Cu" signal "VCC1")
		(22 "In10.Cu" signal "GND4")
		(24 "In11.Cu" signal "IN4")
		(26 "In12.Cu" signal "GND5")
		(28 "In13.Cu" signal "IN5")
		(30 "In14.Cu" signal "GND6")
		(32 "In15.Cu" signal "IN6")
		(34 "In16.Cu" signal "GND7")
		(2 "B.Cu" signal "BOTTOM")
		(9 "F.Adhes" user "F.Adhesive")
		(11 "B.Adhes" user "B.Adhesive")
		(13 "F.Paste" user "Package Geometry/Pastemask Top")
		(15 "B.Paste" user "Package Geometry/Pastemask Bottom")
		(5 "F.SilkS" user "Ref Des/Silkscreen Top")
		(7 "B.SilkS" user "Ref Des/Silkscreen Bottom")
		(1 "F.Mask" user "Board Geometry/Soldermask Top")
		(3 "B.Mask" user "Board Geometry/Soldermask Bottom")
		(17 "Dwgs.User" user "User.Drawings")
		(19 "Cmts.User" user "User.Comments")
		(21 "Eco1.User" user "User.Eco1")
		(23 "Eco2.User" user "User.Eco2")
		(25 "Edge.Cuts" user "Board Geometry/Outline")
		(27 "Margin" user)
		(31 "F.CrtYd" user "Package Geometry/Place Bound Top")
		(29 "B.CrtYd" user "Package Geometry/Place Bound Bottom")
		(35 "F.Fab" user "Ref Des/Assembly Top")
		(33 "B.Fab" user "Ref Des/Assembly Bottom")
	)
	(footprint ""
		(layer "F.Cu")
		(at 312.467752 -395.724634)
		(property "Reference" "U6010"
			(at -6.426454 -7.380224 0)
			(unlocked yes)
			(layer "F.SilkS")
			(effects
				(font
					(size 0.7874 0.5842)
					(thickness 0.1524)
				)
				(justify left)
			)
		)
		(property "Value" ""
			(at 0 0 0)
			(layer "F.Fab")
			(effects
				(font
					(size 1.27 1.27)
				)
			)
		)
		(duplicate_pad_numbers_are_jumpers no)
		(pad "P10" smd circle
			(at 8.802624 -1.431798)
			(size 0.381 0.381)
			(layers "F.Cu" "F.Mask" "F.Paste")
			(net "P5E_CPU0_P0_TX_BUF_DN<15>")
		)
		(pad "P29" smd circle
			(at 8.802624 2.032254)
			(size 0.381 0.381)
			(layers "F.Cu" "F.Mask" "F.Paste")
			(net "P5E_CPU0_P0_RX_DN<15>")
		)
		(pad "R1" smd oval
			(at 8.64997 -3.938524)
			(size 0.254 0.3302)
			(layers "F.Cu" "F.Mask" "F.Paste")
			(net "P5E_CPU0_P0_RX_BUF_DP<15>")
		)
		(pad "R35" smd oval
			(at 8.64997 3.940048)
			(size 0.254 0.3302)
			(layers "F.Cu" "F.Mask" "F.Paste")
			(net "P5E_CPU0_P0_TX_C_DP<15>")
		)
		(pad "T4" smd circle
			(at 8.402574 -2.817368)
			(size 0.381 0.381)
			(layers "F.Cu" "F.Mask" "F.Paste")
			(net "GND")
		)
		(pad "T13" smd circle
			(at 8.402574 -0.79629)
			(size 0.3048 0.3048)
			(layers "F.Cu" "F.Mask" "F.Paste")
			(net "GND")
		)
		(pad "T17" smd circle
			(at 8.402574 -0.296164)
			(size 0.3048 0.3048)
			(layers "F.Cu" "F.Mask" "F.Paste")
			(net "P0V9_CPU0_RT0_2A")
		)
		(pad "T20" smd circle
			(at 8.402574 0.203708)
			(size 0.3048 0.3048)
			(layers "F.Cu" "F.Mask" "F.Paste")
			(net "P0V9_CPU0_RT0_2A")
		)
		(pad "T22" smd circle
			(at 8.402574 0.703834)
			(size 0.3048 0.3048)
			(layers "F.Cu" "F.Mask" "F.Paste")
			(net "GND")
		)
		(pad "T32" smd circle
			(at 8.402574 2.724912)
			(size 0.381 0.381)
			(layers "F.Cu" "F.Mask" "F.Paste")
			(net "GND")
		)
		(pad "U2" smd circle
			(at 8.349996 -3.41884)
			(size 0.3048 0.3048)
			(layers "F.Cu" "F.Mask" "F.Paste")
			(net "GND")
		)
		(pad "U34" smd circle
			(at 8.349996 3.420364)
			(size 0.3048 0.3048)
			(layers "F.Cu" "F.Mask" "F.Paste")
			(net "GND")
		)
		(pad "V1" smd oval
			(at 8.050022 -3.938524)
			(size 0.254 0.3302)
			(layers "F.Cu" "F.Mask" "F.Paste")
			(net "GND")
		)
		(pad "V35" smd oval
			(at 8.050022 3.940048)
			(size 0.254 0.3302)
			(layers "F.Cu" "F.Mask" "F.Paste")
			(net "GND")
		)
		(pad "W7" smd circle
			(at 8.002524 -2.12471)
			(size 0.381 0.381)
			(layers "F.Cu" "F.Mask" "F.Paste")
			(net "P5E_CPU0_P0_TX_BUF_DP<14>")
		)
		(pad "W26" smd circle
			(at 8.002524 1.339342)
			(size 0.381 0.381)
			(layers "F.Cu" "F.Mask" "F.Paste")
			(net "P5E_CPU0_P0_RX_DP<14>")
		)
		(pad "Y2" smd circle
			(at 7.750048 -3.41884)
			(size 0.3048 0.3048)
			(layers "F.Cu" "F.Mask" "F.Paste")
			(net "P5E_CPU0_P0_RX_BUF_DN<14>")
		)
		(pad "Y34" smd circle
			(at 7.750048 3.420364)
			(size 0.3048 0.3048)
			(layers "F.Cu" "F.Mask" "F.Paste")
			(net "P5E_CPU0_P0_TX_C_DN<14>")
		)
	)
)
